(kicad_pcb
	(version 20260206)
	(generator "pcbnew")
	(generator_version "10.0")
	(general
		(thickness 1.6)
		(legacy_teardrops no)
	)
	(paper "A4")
	(title_block
		(title "04192023_DAF0TMB3IC0_F0TG_MB_C_brd_V02_OCP.brd")
		(comment 1 "Grand Teton / footprints 4859-4863 of 8354")
	)
	(layers
		(0 "F.Cu" signal "TOP")
		(4 "In1.Cu" signal "GND")
		(6 "In2.Cu" signal "IN1")
		(8 "In3.Cu" signal "GND1")
		(10 "In4.Cu" signal "IN2")
		(12 "In5.Cu" signal "GND2")
		(14 "In6.Cu" signal "IN3")
		(16 "In7.Cu" signal "GND3")
		(18 "In8.Cu" signal "VCC")
		(20 "In9.Cu" signal "VCC1")
		(22 "In10.Cu" signal "GND4")
		(24 "In11.Cu" signal "IN4")
		(26 "In12.Cu" signal "GND5")
		(28 "In13.Cu" signal "IN5")
		(30 "In14.Cu" signal "GND6")
		(32 "In15.Cu" signal "IN6")
		(34 "In16.Cu" signal "GND7")
		(2 "B.Cu" signal "BOTTOM")
		(9 "F.Adhes" user "F.Adhesive")
		(11 "B.Adhes" user "B.Adhesive")
		(13 "F.Paste" user "Package Geometry/Pastemask Top")
		(15 "B.Paste" user "Package Geometry/Pastemask Bottom")
		(5 "F.SilkS" user "Ref Des/Silkscreen Top")
		(7 "B.SilkS" user "Ref Des/Silkscreen Bottom")
		(1 "F.Mask" user "Board Geometry/Soldermask Top")
		(3 "B.Mask" user "Board Geometry/Soldermask Bottom")
		(17 "Dwgs.User" user "User.Drawings")
		(19 "Cmts.User" user "User.Comments")
		(21 "Eco1.User" user "User.Eco1")
		(23 "Eco2.User" user "User.Eco2")
		(25 "Edge.Cuts" user "Board Geometry/Outline")
		(27 "Margin" user)
		(31 "F.CrtYd" user "Package Geometry/Place Bound Top")
		(29 "B.CrtYd" user "Package Geometry/Place Bound Bottom")
		(35 "F.Fab" user "Ref Des/Assembly Top")
		(33 "B.Fab" user "Ref Des/Assembly Bottom")
	)
	(footprint ""
		(layer "F.Cu")
		(at 447.557652 -18.449798)
		(property "Reference" "PR3786"
			(at 0 0 0)
			(layer "F.SilkS")
			(hide yes)
			(effects
				(font
					(size 1.27 1.27)
				)
			)
		)
		(property "Value" ""
			(at 0 0 0)
			(layer "F.Fab")
			(effects
				(font
					(size 1.27 1.27)
				)
			)
		)
		(duplicate_pad_numbers_are_jumpers no)
		(fp_line
			(start -0.7874 -0.4064)
			(end 0.7874 -0.4064)
			(stroke
				(width 0.1524)
				(type default)
			)
			(layer "F.SilkS")
		)
		(fp_line
			(start -0.7874 0.4064)
			(end -0.7874 -0.4064)
			(stroke
				(width 0.1524)
				(type default)
			)
			(layer "F.SilkS")
		)
		(fp_line
			(start 0.7874 -0.4064)
			(end 0.7874 0.4064)
			(stroke
				(width 0.1524)
				(type default)
			)
			(layer "F.SilkS")
		)
		(fp_line
			(start 0.7874 0.4064)
			(end -0.7874 0.4064)
			(stroke
				(width 0.1524)
				(type default)
			)
			(layer "F.SilkS")
		)
		(fp_line
			(start -0.67945 -0.305054)
			(end -0.12065 -0.305054)
			(stroke
				(width 0.1)
				(type default)
			)
			(layer "F.Fab")
		)
		(fp_line
			(start -0.67945 0.3048)
			(end -0.67945 -0.305054)
			(stroke
				(width 0.1)
				(type default)
			)
			(layer "F.Fab")
		)
		(fp_line
			(start -0.12065 -0.305054)
			(end -0.12065 -0.2794)
			(stroke
				(width 0.1)
				(type default)
			)
			(layer "F.Fab")
		)
		(fp_line
			(start -0.12065 -0.2794)
			(end 0.12065 -0.2794)
			(stroke
				(width 0.1)
				(type default)
			)
			(layer "F.Fab")
		)
		(fp_line
			(start -0.12065 0.2794)
			(end -0.12065 0.3048)
			(stroke
				(width 0.1)
				(type default)
			)
			(layer "F.Fab")
		)
		(fp_line
			(start -0.12065 0.3048)
			(end -0.67945 0.3048)
			(stroke
				(width 0.1)
				(type default)
			)
			(layer "F.Fab")
		)
		(fp_line
			(start 0.120396 0.2794)
			(end -0.12065 0.2794)
			(stroke
				(width 0.1)
				(type default)
			)
			(layer "F.Fab")
		)
		(fp_line
			(start 0.120396 0.3048)
			(end 0.120396 0.2794)
			(stroke
				(width 0.1)
				(type default)
			)
			(layer "F.Fab")
		)
		(fp_line
			(start 0.12065 -0.3048)
			(end 0.67945 -0.3048)
			(stroke
				(width 0.1)
				(type default)
			)
			(layer "F.Fab")
		)
		(fp_line
			(start 0.12065 -0.2794)
			(end 0.12065 -0.3048)
			(stroke
				(width 0.1)
				(type default)
			)
			(layer "F.Fab")
		)
		(fp_line
			(start 0.67945 -0.3048)
			(end 0.67945 0.3048)
			(stroke
				(width 0.1)
				(type default)
			)
			(layer "F.Fab")
		)
		(fp_line
			(start 0.67945 0.3048)
			(end 0.120396 0.3048)
			(stroke
				(width 0.1)
				(type default)
			)
			(layer "F.Fab")
		)
		(pad "1" smd circle
			(at -0.40005 0)
			(size 0 0)
			(layers "F.Cu" "F.Mask" "F.Paste")
			(net "P12V_AUX")
		)
		(pad "2" smd circle
			(at 0.40005 0)
			(size 0 0)
			(layers "F.Cu" "F.Mask" "F.Paste")
			(net "P12V_OCP_UV_1")
		)
	)
	(footprint ""
		(layer "F.Cu")
		(at 239.152684 -54.736238)
		(property "Reference" "C1994"
			(at 0 0 0)
			(layer "F.SilkS")
			(hide yes)
			(effects
				(font
					(size 1.27 1.27)
				)
			)
		)
		(property "Value" ""
			(at 0 0 0)
			(layer "F.Fab")
			(effects
				(font
					(size 1.27 1.27)
				)
			)
		)
		(duplicate_pad_numbers_are_jumpers no)
		(fp_line
			(start -0.299974 -0.150114)
			(end 0.299974 -0.150114)
			(stroke
				(width 0.1)
				(type default)
			)
			(layer "F.Fab")
		)
		(fp_line
			(start -0.299974 0.150114)
			(end -0.299974 -0.150114)
			(stroke
				(width 0.1)
				(type default)
			)
			(layer "F.Fab")
		)
		(fp_line
			(start 0.299974 -0.150114)
			(end 0.299974 0.150114)
			(stroke
				(width 0.1)
				(type default)
			)
			(layer "F.Fab")
		)
		(fp_line
			(start 0.299974 0.150114)
			(end -0.299974 0.150114)
			(stroke
				(width 0.1)
				(type default)
			)
			(layer "F.Fab")
		)
		(pad "1" smd rect
			(at -0.2667 0)
			(size 0.3048 0.381)
			(layers "F.Cu" "F.Mask" "F.Paste")
			(net "P3E_CPU0_P4_TX_C_DN<1>")
		)
		(pad "2" smd rect
			(at 0.2667 0)
			(size 0.3048 0.381)
			(layers "F.Cu" "F.Mask" "F.Paste")
			(net "P3E_CPU0_P4_TX_DN<1>")
		)
	)
	(footprint ""
		(layer "F.Cu")
		(at 99.07397 -182.693056 180)
		(property "Reference" "PU27"
			(at 0.78994 -6.592062 0)
			(unlocked yes)
			(layer "F.SilkS")
			(effects
				(font
					(size 0.7874 0.5842)
					(thickness 0.1524)
				)
				(justify left)
			)
		)
		(property "Value" ""
			(at 0 0 180)
			(layer "F.Fab")
			(effects
				(font
					(size 1.27 1.27)
				)
			)
		)
		(duplicate_pad_numbers_are_jumpers no)
		(fp_line
			(start 2.500122 2.999994)
			(end 2.2987 2.999994)
			(stroke
				(width 0.1524)
				(type default)
			)
			(layer "F.SilkS")
		)
		(fp_line
			(start 2.500122 2.339594)
			(end 2.500122 2.999994)
			(stroke
				(width 0.1524)
				(type default)
			)
			(layer "F.SilkS")
		)
		(fp_line
			(start 2.500122 -2.999994)
			(end 2.500122 -2.44348)
			(stroke
				(width 0.1524)
				(type default)
			)
			(layer "F.SilkS")
		)
		(fp_line
			(start 2.31394 -2.999994)
			(end 2.500122 -2.999994)
			(stroke
				(width 0.1524)
				(type default)
			)
			(layer "F.SilkS")
		)
		(fp_line
			(start -2.2987 2.999994)
			(end -2.500122 2.999994)
			(stroke
				(width 0.1524)
				(type default)
			)
			(layer "F.SilkS")
		)
		(fp_line
			(start -2.500122 2.999994)
			(end -2.500122 2.339594)
			(stroke
				(width 0.1524)
				(type default)
			)
			(layer "F.SilkS")
		)
		(fp_line
			(start -2.500122 0.6604)
			(end -2.500122 0.229108)
			(stroke
				(width 0.1524)
				(type default)
			)
			(layer "F.SilkS")
		)
		(fp_line
			(start -2.500122 -2.529078)
			(end -2.500122 -2.999994)
			(stroke
				(width 0.1524)
				(type default)
			)
			(layer "F.SilkS")
		)
		(fp_line
			(start -2.500122 -2.999994)
			(end -2.24409 -2.999994)
			(stroke
				(width 0.1524)
				(type default)
			)
			(layer "F.SilkS")
		)
		(fp_poly
			(pts
				(xy -2.770632 -2.436368) (xy -3.443986 -2.660904) (xy -2.995168 -3.109722)
			)
			(stroke
				(width 0)
				(type default)
			)
			(fill yes)
			(layer "F.SilkS")
		)
		(fp_line
			(start 2.500122 2.999994)
			(end -2.500122 2.999994)
			(stroke
				(width 0.1)
				(type default)
			)
			(layer "F.Fab")
		)
		(fp_line
			(start 2.500122 -2.999994)
			(end 2.500122 2.999994)
			(stroke
				(width 0.1)
				(type default)
			)
			(layer "F.Fab")
		)
		(fp_line
			(start -2.500122 2.999994)
			(end -2.500122 -2.999994)
			(stroke
				(width 0.1)
				(type default)
			)
			(layer "F.Fab")
		)
		(fp_line
			(start -2.500122 -2.999994)
			(end 2.500122 -2.999994)
			(stroke
				(width 0.1)
				(type default)
			)
			(layer "F.Fab")
		)
		(fp_poly
			(pts
				(xy -4.218432 -2.783078) (xy -4.218432 -1.767078) (xy -3.202432 -2.275078)
			)
			(stroke
				(width 0)
				(type default)
			)
			(fill yes)
			(layer "F.Fab")
		)
		(pad "1" smd rect
			(at -2.400046 -2.275078 270)
			(size 0.2286 0.6096)
			(layers "F.Cu" "F.Mask" "F.Paste")
			(net "PVDDCR_CPU0_P1_VOS3")
		)
		(pad "2" smd rect
			(at -2.400046 -1.82499 270)
			(size 0.2286 0.6096)
			(layers "F.Cu" "F.Mask" "F.Paste")
			(net "GND")
		)
		(pad "3" smd rect
			(at -2.400046 -1.374902 270)
			(size 0.2286 0.6096)
			(layers "F.Cu" "F.Mask" "F.Paste")
			(net "PVDDCR_CPU0_P1_VCC3")
		)
		(pad "4" smd rect
			(at -2.400046 -0.925068 270)
			(size 0.2286 0.6096)
			(layers "F.Cu" "F.Mask" "F.Paste")
			(net "PVDDCR_CPU0_P1_PVCC")
		)
		(pad "5" smd rect
			(at -2.400046 -0.47498 270)
			(size 0.2286 0.6096)
			(layers "F.Cu" "F.Mask" "F.Paste")
			(net "GND")
		)
		(pad "6" smd rect
			(at -2.400046 -0.024892 270)
			(size 0.2286 0.6096)
			(layers "F.Cu" "F.Mask" "F.Paste")
			(net "NC_PVDDCR_CPU0_P1_GL1_3")
		)
		(pad "7_9-20_24" smd circle
			(at 0 1.150112 270)
			(size 0 0)
			(layers "F.Cu" "F.Mask" "F.Paste")
			(net "GND")
		)
		(pad "10_19" smd rect
			(at 0 2.899918 270)
			(size 0.6096 4.318)
			(layers "F.Cu" "F.Mask" "F.Paste")
			(net "SW_PVDDCR_CPU0_P1_SW3")
		)
		(pad "25_29" smd rect
			(at 1.549908 -1.279906 90)
			(size 2.0574 2.3114)
			(layers "F.Cu" "F.Mask" "F.Paste")
			(net "SW_P12V_AUX_PVDDCR_CPU0_P1_FLT")
		)
		(pad "30" smd rect
			(at 2.05994 -2.899918 180)
			(size 0.2286 0.6096)
			(layers "F.Cu" "F.Mask" "F.Paste")
			(net "SW_P12V_AUX_PVDDCR_CPU0_P1_FLT")
		)
		(pad "31" smd rect
			(at 1.610106 -2.899918 180)
			(size 0.2286 0.6096)
			(layers "F.Cu" "F.Mask" "F.Paste")
			(net "NC_PVDDCR_CPU0_P1_DNC3")
		)
		(pad "32" smd rect
			(at 1.160018 -2.899918 180)
			(size 0.2286 0.6096)
			(layers "F.Cu" "F.Mask" "F.Paste")
			(net "SW_PVDDCR_CPU0_P1_PH3")
		)
		(pad "33" smd rect
			(at 0.70993 -2.899918 180)
			(size 0.2286 0.6096)
			(layers "F.Cu" "F.Mask" "F.Paste")
			(net "SW_PVDDCR_CPU0_P1_BOOT3")
		)
		(pad "34" smd rect
			(at 0.260096 -2.899918 180)
			(size 0.2286 0.6096)
			(layers "F.Cu" "F.Mask" "F.Paste")
			(net "PVDDCR_CPU0_P1_PWM3")
		)
		(pad "35" smd rect
			(at -0.189992 -2.899918 180)
			(size 0.2286 0.6096)
			(layers "F.Cu" "F.Mask" "F.Paste")
			(net "PVDDCR_CPU0_P1_VCC3")
		)
		(pad "36" smd rect
			(at -0.64008 -2.899918 180)
			(size 0.2286 0.6096)
			(layers "F.Cu" "F.Mask" "F.Paste")
			(net "PVDDCR_CPU0_P1_TEMP0")
		)
		(pad "37" smd rect
			(at -1.089914 -2.899918 180)
			(size 0.2286 0.6096)
			(layers "F.Cu" "F.Mask" "F.Paste")
			(net "PVDDCR_CPU0_P1_LSET3")
		)
		(pad "38" smd rect
			(at -1.540002 -2.899918 180)
			(size 0.2286 0.6096)
			(layers "F.Cu" "F.Mask" "F.Paste")
			(net "PVDDCR_CPU0_P1_IMON3")
		)
		(pad "39" smd rect
			(at -1.99009 -2.899918 180)
			(size 0.2286 0.6096)
			(layers "F.Cu" "F.Mask" "F.Paste")
			(net "PVDDCR_CPU0_P1_VCCS")
		)
		(pad "40" smd rect
			(at -0.87503 -1.27508 180)
			(size 1.7526 1.9558)
			(layers "F.Cu" "F.Mask" "F.Paste")
			(net "GND")
		)
		(pad "41" smd rect
			(at -1.525016 0.249936 90)
			(size 0.3048 0.4572)
			(layers "F.Cu" "F.Mask" "F.Paste")
			(net "NC_PVDDCR_CPU0_P1_GL2_3")
		)
		(zone
			(layer "F.Cu")
			(hatch none 0.5)
			(connect_pads
				(clearance 0)
			)
			(min_thickness 0.25)
			(keepout
				(tracks not_allowed)
				(vias allowed)
				(pads allowed)
				(copperpour not_allowed)
				(footprints allowed)
			)
			(placement
				(enabled no)
				(sheetname "")
			)
			(fill
				(thermal_gap 0.5)
				(thermal_bridge_width 0.5)
				(island_removal_mode 0)
			)
			(polygon
				(pts
					(xy 101.574092 -185.237374) (xy 101.574092 -184.94375) (xy 96.573848 -184.94375) (xy 96.573848 -185.237374)
					(xy 96.86417 -185.237374) (xy 101.28377 -185.237374)
				)
			)
		)
		(zone
			(layer "F.Cu")
			(hatch none 0.5)
			(connect_pads
				(clearance 0)
			)
			(min_thickness 0.25)
			(keepout
				(tracks not_allowed)
				(vias allowed)
				(pads allowed)
				(copperpour not_allowed)
				(footprints allowed)
			)
			(placement
				(enabled no)
				(sheetname "")
			)
			(fill
				(thermal_gap 0.5)
				(thermal_bridge_width 0.5)
				(island_removal_mode 0)
			)
			(polygon
				(pts
					(xy 99.0219 -182.446676) (xy 99.0219 -180.389276) (xy 100.8761 -180.389276) (xy 100.8761 -180.630322)
					(xy 101.118416 -180.630322) (xy 101.118416 -180.148738) (xy 97.178368 -180.148738) (xy 97.178368 -180.33365)
					(xy 98.730562 -180.33365) (xy 98.730562 -182.49265) (xy 96.573848 -182.49265) (xy 96.573848 -182.742332)
					(xy 98.726244 -182.742332)
				)
			)
		)
	)
	(footprint ""
		(layer "F.Cu")
		(at 127.381 -106.934 90)
		(property "Reference" "R8113"
			(at 0 0 90)
			(layer "F.SilkS")
			(hide yes)
			(effects
				(font
					(size 1.27 1.27)
				)
			)
		)
		(property "Value" ""
			(at 0 0 90)
			(layer "F.Fab")
			(effects
				(font
					(size 1.27 1.27)
				)
			)
		)
		(duplicate_pad_numbers_are_jumpers no)
		(fp_line
			(start 0.7874 -0.4064)
			(end 0.7874 0.4064)
			(stroke
				(width 0.1524)
				(type default)
			)
			(layer "F.SilkS")
		)
		(fp_line
			(start -0.7874 -0.4064)
			(end 0.7874 -0.4064)
			(stroke
				(width 0.1524)
				(type default)
			)
			(layer "F.SilkS")
		)
		(fp_line
			(start 0.7874 0.4064)
			(end -0.7874 0.4064)
			(stroke
				(width 0.1524)
				(type default)
			)
			(layer "F.SilkS")
		)
		(fp_line
			(start -0.7874 0.4064)
			(end -0.7874 -0.4064)
			(stroke
				(width 0.1524)
				(type default)
			)
			(layer "F.SilkS")
		)
		(fp_line
			(start -0.12065 -0.305054)
			(end -0.12065 -0.2794)
			(stroke
				(width 0.1)
				(type default)
			)
			(layer "F.Fab")
		)
		(fp_line
			(start -0.67945 -0.305054)
			(end -0.12065 -0.305054)
			(stroke
				(width 0.1)
				(type default)
			)
			(layer "F.Fab")
		)
		(fp_line
			(start 0.67945 -0.3048)
			(end 0.67945 0.3048)
			(stroke
				(width 0.1)
				(type default)
			)
			(layer "F.Fab")
		)
		(fp_line
			(start 0.12065 -0.3048)
			(end 0.67945 -0.3048)
			(stroke
				(width 0.1)
				(type default)
			)
			(layer "F.Fab")
		)
		(fp_line
			(start 0.12065 -0.2794)
			(end 0.12065 -0.3048)
			(stroke
				(width 0.1)
				(type default)
			)
			(layer "F.Fab")
		)
		(fp_line
			(start -0.12065 -0.2794)
			(end 0.12065 -0.2794)
			(stroke
				(width 0.1)
				(type default)
			)
			(layer "F.Fab")
		)
		(fp_line
			(start 0.120396 0.2794)
			(end -0.12065 0.2794)
			(stroke
				(width 0.1)
				(type default)
			)
			(layer "F.Fab")
		)
		(fp_line
			(start -0.12065 0.2794)
			(end -0.12065 0.3048)
			(stroke
				(width 0.1)
				(type default)
			)
			(layer "F.Fab")
		)
		(fp_line
			(start 0.67945 0.3048)
			(end 0.120396 0.3048)
			(stroke
				(width 0.1)
				(type default)
			)
			(layer "F.Fab")
		)
		(fp_line
			(start 0.120396 0.3048)
			(end 0.120396 0.2794)
			(stroke
				(width 0.1)
				(type default)
			)
			(layer "F.Fab")
		)
		(fp_line
			(start -0.12065 0.3048)
			(end -0.67945 0.3048)
			(stroke
				(width 0.1)
				(type default)
			)
			(layer "F.Fab")
		)
		(fp_line
			(start -0.67945 0.3048)
			(end -0.67945 -0.305054)
			(stroke
				(width 0.1)
				(type default)
			)
			(layer "F.Fab")
		)
		(pad "1" smd circle
			(at -0.40005 0 90)
			(size 0 0)
			(layers "F.Cu" "F.Mask" "F.Paste")
			(net "P3V3_AUX")
		)
		(pad "2" smd circle
			(at 0.40005 0 90)
			(size 0 0)
			(layers "F.Cu" "F.Mask" "F.Paste")
			(net "UV_ADR_P2V5_COMP")
		)
	)
	(footprint ""
		(layer "F.Cu")
		(at 110.152942 -19.9898 90)
		(property "Reference" "R6273"
			(at 0 0 90)
			(layer "F.SilkS")
			(hide yes)
			(effects
				(font
					(size 1.27 1.27)
				)
			)
		)
		(property "Value" ""
			(at 0 0 90)
			(layer "F.Fab")
			(effects
				(font
					(size 1.27 1.27)
				)
			)
		)
		(duplicate_pad_numbers_are_jumpers no)
		(fp_line
			(start 0.7874 -0.4064)
			(end 0.7874 0.4064)
			(stroke
				(width 0.1524)
				(type default)
			)
			(layer "F.SilkS")
		)
		(fp_line
			(start -0.7874 -0.4064)
			(end 0.7874 -0.4064)
			(stroke
				(width 0.1524)
				(type default)
			)
			(layer "F.SilkS")
		)
		(fp_line
			(start 0.7874 0.4064)
			(end -0.7874 0.4064)
			(stroke
				(width 0.1524)
				(type default)
			)
			(layer "F.SilkS")
		)
		(fp_line
			(start -0.7874 0.4064)
			(end -0.7874 -0.4064)
			(stroke
				(width 0.1524)
				(type default)
			)
			(layer "F.SilkS")
		)
		(fp_line
			(start -0.12065 -0.305054)
			(end -0.12065 -0.2794)
			(stroke
				(width 0.1)
				(type default)
			)
			(layer "F.Fab")
		)
		(fp_line
			(start -0.67945 -0.305054)
			(end -0.12065 -0.305054)
			(stroke
				(width 0.1)
				(type default)
			)
			(layer "F.Fab")
		)
		(fp_line
			(start 0.67945 -0.3048)
			(end 0.67945 0.3048)
			(stroke
				(width 0.1)
				(type default)
			)
			(layer "F.Fab")
		)
		(fp_line
			(start 0.12065 -0.3048)
			(end 0.67945 -0.3048)
			(stroke
				(width 0.1)
				(type default)
			)
			(layer "F.Fab")
		)
		(fp_line
			(start 0.12065 -0.2794)
			(end 0.12065 -0.3048)
			(stroke
				(width 0.1)
				(type default)
			)
			(layer "F.Fab")
		)
		(fp_line
			(start -0.12065 -0.2794)
			(end 0.12065 -0.2794)
			(stroke
				(width 0.1)
				(type default)
			)
			(layer "F.Fab")
		)
		(fp_line
			(start 0.120396 0.2794)
			(end -0.12065 0.2794)
			(stroke
				(width 0.1)
				(type default)
			)
			(layer "F.Fab")
		)
		(fp_line
			(start -0.12065 0.2794)
			(end -0.12065 0.3048)
			(stroke
				(width 0.1)
				(type default)
			)
			(layer "F.Fab")
		)
		(fp_line
			(start 0.67945 0.3048)
			(end 0.120396 0.3048)
			(stroke
				(width 0.1)
				(type default)
			)
			(layer "F.Fab")
		)
		(fp_line
			(start 0.120396 0.3048)
			(end 0.120396 0.2794)
			(stroke
				(width 0.1)
				(type default)
			)
			(layer "F.Fab")
		)
		(fp_line
			(start -0.12065 0.3048)
			(end -0.67945 0.3048)
			(stroke
				(width 0.1)
				(type default)
			)
			(layer "F.Fab")
		)
		(fp_line
			(start -0.67945 0.3048)
			(end -0.67945 -0.305054)
			(stroke
				(width 0.1)
				(type default)
			)
			(layer "F.Fab")
		)
		(pad "1" smd circle
			(at -0.40005 0 90)
			(size 0 0)
			(layers "F.Cu" "F.Mask" "F.Paste")
			(net "P3V3_AUX")
		)
		(pad "2" smd circle
			(at 0.40005 0 90)
			(size 0 0)
			(layers "F.Cu" "F.Mask" "F.Paste")
			(net "USB_HUB2_MRP_CFG_STRAP")
		)
	)
)
